# S9S_MB_2U (Grand Teton) — schematic netlist excerpt (pin names and nets, part order shuffled) for the footprints in the layout excerpt that follows; sources: Cadence DE-HDL packaged netlist, KiCad conversion of 03242023_DA0F0TMBIJ0_F0T_Motherboard_J_brd_V01_OCP.brd

R381  Q_RES  10K 1% CHIP  pkg 0402LF  page 198 : A = FM_FLASH_SECURITY_STRAP ; B = GND
D76  Q_LED  IC  pkg SMLF  page 253 : A = LED_PWRGD_PVCCFA_EHV_FIVRA_CPU0 ; C = LED_PWRGD_PVCCFA_EHV_FIVRA_CP_1

(kicad_pcb
	(version 20260206)
	(generator "pcbnew")
	(generator_version "10.0")
	(general
		(thickness 1.6)
		(legacy_teardrops no)
	)
	(paper "A4")
	(title_block
		(title "03242023_DA0F0TMBIJ0_F0T_Motherboard_J_brd_V01_OCP.brd")
		(comment 1 "Grand Teton / footprints 873-874 of 6105")
	)
	(layers
		(0 "F.Cu" signal "TOP")
		(4 "In1.Cu" signal "GND")
		(6 "In2.Cu" signal "IN1")
		(8 "In3.Cu" signal "GND1")
		(10 "In4.Cu" signal "IN2")
		(12 "In5.Cu" signal "GND2")
		(14 "In6.Cu" signal "IN3")
		(16 "In7.Cu" signal "GND3")
		(18 "In8.Cu" signal "VCC")
		(20 "In9.Cu" signal "VCC1")
		(22 "In10.Cu" signal "GND4")
		(24 "In11.Cu" signal "IN4")
		(26 "In12.Cu" signal "GND5")
		(28 "In13.Cu" signal "IN5")
		(30 "In14.Cu" signal "GND6")
		(32 "In15.Cu" signal "IN6")
		(34 "In16.Cu" signal "GND7")
		(2 "B.Cu" signal "BOTTOM")
		(9 "F.Adhes" user "F.Adhesive")
		(11 "B.Adhes" user "B.Adhesive")
		(13 "F.Paste" user "Package Geometry/Pastemask Top")
		(15 "B.Paste" user "Package Geometry/Pastemask Bottom")
		(5 "F.SilkS" user "Ref Des/Silkscreen Top")
		(7 "B.SilkS" user "Ref Des/Silkscreen Bottom")
		(1 "F.Mask" user "Board Geometry/Soldermask Top")
		(3 "B.Mask" user "Board Geometry/Soldermask Bottom")
		(17 "Dwgs.User" user "User.Drawings")
		(19 "Cmts.User" user "User.Comments")
		(21 "Eco1.User" user "User.Eco1")
		(23 "Eco2.User" user "User.Eco2")
		(25 "Edge.Cuts" user "Board Geometry/Outline")
		(27 "Margin" user)
		(31 "F.CrtYd" user "Package Geometry/Place Bound Top")
		(29 "B.CrtYd" user "Package Geometry/Place Bound Bottom")
		(35 "F.Fab" user "Ref Des/Assembly Top")
		(33 "B.Fab" user "Ref Des/Assembly Bottom")
	)
	(footprint ""
		(layer "F.Cu")
		(at 309.522622 -42.916348 180)
		(property "Reference" "R381"
			(at 0 0 180)
			(layer "F.SilkS")
			(hide yes)
			(effects
				(font
					(size 1.27 1.27)
				)
			)
		)
		(property "Value" ""
			(at 0 0 180)
			(layer "F.Fab")
			(effects
				(font
					(size 1.27 1.27)
				)
			)
		)
		(duplicate_pad_numbers_are_jumpers no)
		(fp_line
			(start 0.7874 0.4064)
			(end -0.7874 0.4064)
			(stroke
				(width 0.1524)
				(type default)
			)
			(layer "F.SilkS")
		)
		(fp_line
			(start 0.7874 -0.4064)
			(end 0.7874 0.4064)
			(stroke
				(width 0.1524)
				(type default)
			)
			(layer "F.SilkS")
		)
		(fp_line
			(start -0.7874 0.4064)
			(end -0.7874 -0.4064)
			(stroke
				(width 0.1524)
				(type default)
			)
			(layer "F.SilkS")
		)
		(fp_line
			(start -0.7874 -0.4064)
			(end 0.7874 -0.4064)
			(stroke
				(width 0.1524)
				(type default)
			)
			(layer "F.SilkS")
		)
		(fp_line
			(start 0.67945 0.3048)
			(end 0.120396 0.3048)
			(stroke
				(width 0.1)
				(type default)
			)
			(layer "F.Fab")
		)
		(fp_line
			(start 0.67945 -0.3048)
			(end 0.67945 0.3048)
			(stroke
				(width 0.1)
				(type default)
			)
			(layer "F.Fab")
		)
		(fp_line
			(start 0.12065 -0.2794)
			(end 0.12065 -0.3048)
			(stroke
				(width 0.1)
				(type default)
			)
			(layer "F.Fab")
		)
		(fp_line
			(start 0.12065 -0.3048)
			(end 0.67945 -0.3048)
			(stroke
				(width 0.1)
				(type default)
			)
			(layer "F.Fab")
		)
		(fp_line
			(start 0.120396 0.3048)
			(end 0.120396 0.2794)
			(stroke
				(width 0.1)
				(type default)
			)
			(layer "F.Fab")
		)
		(fp_line
			(start 0.120396 0.2794)
			(end -0.12065 0.2794)
			(stroke
				(width 0.1)
				(type default)
			)
			(layer "F.Fab")
		)
		(fp_line
			(start -0.12065 0.3048)
			(end -0.67945 0.3048)
			(stroke
				(width 0.1)
				(type default)
			)
			(layer "F.Fab")
		)
		(fp_line
			(start -0.12065 0.2794)
			(end -0.12065 0.3048)
			(stroke
				(width 0.1)
				(type default)
			)
			(layer "F.Fab")
		)
		(fp_line
			(start -0.12065 -0.2794)
			(end 0.12065 -0.2794)
			(stroke
				(width 0.1)
				(type default)
			)
			(layer "F.Fab")
		)
		(fp_line
			(start -0.12065 -0.305054)
			(end -0.12065 -0.2794)
			(stroke
				(width 0.1)
				(type default)
			)
			(layer "F.Fab")
		)
		(fp_line
			(start -0.67945 0.3048)
			(end -0.67945 -0.305054)
			(stroke
				(width 0.1)
				(type default)
			)
			(layer "F.Fab")
		)
		(fp_line
			(start -0.67945 -0.305054)
			(end -0.12065 -0.305054)
			(stroke
				(width 0.1)
				(type default)
			)
			(layer "F.Fab")
		)
		(pad "1" smd circle
			(at -0.40005 0 180)
			(size 0 0)
			(layers "F.Cu" "F.Mask" "F.Paste")
			(net "FM_FLASH_SECURITY_STRAP")
		)
		(pad "2" smd circle
			(at 0.40005 0 180)
			(size 0 0)
			(layers "F.Cu" "F.Mask" "F.Paste")
			(net "GND")
		)
	)
	(footprint ""
		(layer "F.Cu")
		(at 64.793876 -79.078836)
		(property "Reference" "D76"
			(at -34.444686 34.341308 90)
			(unlocked yes)
			(layer "F.SilkS")
			(effects
				(font
					(size 0.635 0.4064)
					(thickness 0.1524)
				)
				(justify left)
			)
		)
		(property "Value" ""
			(at 0 0 0)
			(layer "F.Fab")
			(effects
				(font
					(size 1.27 1.27)
				)
			)
		)
		(duplicate_pad_numbers_are_jumpers no)
		(fp_line
			(start -0.90678 0.4826)
			(end -0.90678 -0.4699)
			(stroke
				(width 0.1524)
				(type default)
			)
			(layer "F.SilkS")
		)
		(fp_line
			(start -0.89408 -0.4826)
			(end 0.90678 -0.4826)
			(stroke
				(width 0.1524)
				(type default)
			)
			(layer "F.SilkS")
		)
		(fp_line
			(start -0.79248 -0.4826)
			(end 1.03378 -0.4826)
			(stroke
				(width 0.1524)
				(type default)
			)
			(layer "F.SilkS")
		)
		(fp_line
			(start -0.64008 -0.4826)
			(end 1.16078 -0.4826)
			(stroke
				(width 0.1524)
				(type default)
			)
			(layer "F.SilkS")
		)
		(fp_line
			(start 0.90678 -0.4826)
			(end 0.90678 0.4826)
			(stroke
				(width 0.1524)
				(type default)
			)
			(layer "F.SilkS")
		)
		(fp_line
			(start 0.90678 0.4826)
			(end -0.90678 0.4826)
			(stroke
				(width 0.1524)
				(type default)
			)
			(layer "F.SilkS")
		)
		(fp_line
			(start 1.03378 -0.4826)
			(end 1.03378 0.4826)
			(stroke
				(width 0.1524)
				(type default)
			)
			(layer "F.SilkS")
		)
		(fp_line
			(start 1.03378 0.4826)
			(end -0.79248 0.4826)
			(stroke
				(width 0.1524)
				(type default)
			)
			(layer "F.SilkS")
		)
		(fp_line
			(start 1.16078 -0.4826)
			(end 1.16078 0.4826)
			(stroke
				(width 0.1524)
				(type default)
			)
			(layer "F.SilkS")
		)
		(fp_line
			(start 1.16078 0.4826)
			(end -0.64008 0.4826)
			(stroke
				(width 0.1524)
				(type default)
			)
			(layer "F.SilkS")
		)
		(fp_line
			(start -0.499872 -0.249936)
			(end 0.499872 -0.249936)
			(stroke
				(width 0.1)
				(type default)
			)
			(layer "F.Fab")
		)
		(fp_line
			(start -0.499872 0.249936)
			(end -0.499872 -0.249936)
			(stroke
				(width 0.1)
				(type default)
			)
			(layer "F.Fab")
		)
		(fp_line
			(start 0.499872 -0.249936)
			(end 0.499872 0.249936)
			(stroke
				(width 0.1)
				(type default)
			)
			(layer "F.Fab")
		)
		(fp_line
			(start 0.499872 0.249936)
			(end -0.499872 0.249936)
			(stroke
				(width 0.1)
				(type default)
			)
			(layer "F.Fab")
		)
		(pad "A" smd rect
			(at -0.47498 0)
			(size 0.6096 0.7112)
			(layers "F.Cu" "F.Mask" "F.Paste")
			(net "LED_PWRGD_PVCCFA_EHV_FIVRA_CPU0")
		)
		(pad "C" smd rect
			(at 0.47498 0)
			(size 0.6096 0.7112)
			(layers "F.Cu" "F.Mask" "F.Paste")
			(net "LED_PWRGD_PVCCFA_EHV_FIVRA_CP_1")
		)
	)
)
